(kicad_pcb
	(version 20260206)
	(generator "pcbnew")
	(generator_version "10.0")
	(general
		(thickness 1.6)
		(legacy_teardrops no)
	)
	(paper "A4")
	(title_block
		(title "01162023_DA0F0TEBIF0_F0T_Expander_BD_F_brd_V02_OCP.brd")
		(comment 1 "Grand Teton / footprints 844-850 of 9728")
	)
	(layers
		(0 "F.Cu" signal "TOP")
		(4 "In1.Cu" signal "GND")
		(6 "In2.Cu" signal "VCC")
		(8 "In3.Cu" signal "VCC1")
		(10 "In4.Cu" signal "GND1")
		(12 "In5.Cu" signal "IN1")
		(14 "In6.Cu" signal "GND2")
		(16 "In7.Cu" signal "IN2")
		(18 "In8.Cu" signal "GND3")
		(20 "In9.Cu" signal "IN3")
		(22 "In10.Cu" signal "GND4")
		(24 "In11.Cu" signal "IN4")
		(26 "In12.Cu" signal "GND5")
		(28 "In13.Cu" signal "IN5")
		(30 "In14.Cu" signal "GND6")
		(32 "In15.Cu" signal "IN6")
		(34 "In16.Cu" signal "GND7")
		(2 "B.Cu" signal "BOTTOM")
		(9 "F.Adhes" user "F.Adhesive")
		(11 "B.Adhes" user "B.Adhesive")
		(13 "F.Paste" user "Package Geometry/Pastemask Top")
		(15 "B.Paste" user "Package Geometry/Pastemask Bottom")
		(5 "F.SilkS" user "Ref Des/Silkscreen Top")
		(7 "B.SilkS" user "Ref Des/Silkscreen Bottom")
		(1 "F.Mask" user "Board Geometry/Soldermask Top")
		(3 "B.Mask" user "Board Geometry/Soldermask Bottom")
		(17 "Dwgs.User" user "User.Drawings")
		(19 "Cmts.User" user "User.Comments")
		(21 "Eco1.User" user "User.Eco1")
		(23 "Eco2.User" user "User.Eco2")
		(25 "Edge.Cuts" user "Board Geometry/Outline")
		(27 "Margin" user)
		(31 "F.CrtYd" user "Package Geometry/Place Bound Top")
		(29 "B.CrtYd" user "Package Geometry/Place Bound Bottom")
		(35 "F.Fab" user "Ref Des/Assembly Top")
		(33 "B.Fab" user "Ref Des/Assembly Bottom")
	)
	(footprint ""
		(layer "F.Cu")
		(at 13.764768 -162.003994 90)
		(property "Reference" "PC614"
			(at 0 0 90)
			(layer "F.SilkS")
			(hide yes)
			(effects
				(font
					(size 1.27 1.27)
				)
			)
		)
		(property "Value" ""
			(at 0 0 90)
			(layer "F.Fab")
			(effects
				(font
					(size 1.27 1.27)
				)
			)
		)
		(duplicate_pad_numbers_are_jumpers no)
		(fp_line
			(start 0.7874 -0.4064)
			(end 0.7874 0.4064)
			(stroke
				(width 0.1524)
				(type default)
			)
			(layer "F.SilkS")
		)
		(fp_line
			(start -0.7874 -0.4064)
			(end 0.7874 -0.4064)
			(stroke
				(width 0.1524)
				(type default)
			)
			(layer "F.SilkS")
		)
		(fp_line
			(start 0.7874 0.4064)
			(end -0.7874 0.4064)
			(stroke
				(width 0.1524)
				(type default)
			)
			(layer "F.SilkS")
		)
		(fp_line
			(start -0.7874 0.4064)
			(end -0.7874 -0.4064)
			(stroke
				(width 0.1524)
				(type default)
			)
			(layer "F.SilkS")
		)
		(fp_line
			(start -0.12065 -0.305054)
			(end -0.12065 -0.2794)
			(stroke
				(width 0.1)
				(type default)
			)
			(layer "F.Fab")
		)
		(fp_line
			(start -0.67945 -0.305054)
			(end -0.12065 -0.305054)
			(stroke
				(width 0.1)
				(type default)
			)
			(layer "F.Fab")
		)
		(fp_line
			(start 0.67945 -0.3048)
			(end 0.67945 0.3048)
			(stroke
				(width 0.1)
				(type default)
			)
			(layer "F.Fab")
		)
		(fp_line
			(start 0.12065 -0.3048)
			(end 0.67945 -0.3048)
			(stroke
				(width 0.1)
				(type default)
			)
			(layer "F.Fab")
		)
		(fp_line
			(start 0.12065 -0.2794)
			(end 0.12065 -0.3048)
			(stroke
				(width 0.1)
				(type default)
			)
			(layer "F.Fab")
		)
		(fp_line
			(start -0.12065 -0.2794)
			(end 0.12065 -0.2794)
			(stroke
				(width 0.1)
				(type default)
			)
			(layer "F.Fab")
		)
		(fp_line
			(start 0.120396 0.2794)
			(end -0.12065 0.2794)
			(stroke
				(width 0.1)
				(type default)
			)
			(layer "F.Fab")
		)
		(fp_line
			(start -0.12065 0.2794)
			(end -0.12065 0.3048)
			(stroke
				(width 0.1)
				(type default)
			)
			(layer "F.Fab")
		)
		(fp_line
			(start 0.67945 0.3048)
			(end 0.120396 0.3048)
			(stroke
				(width 0.1)
				(type default)
			)
			(layer "F.Fab")
		)
		(fp_line
			(start 0.120396 0.3048)
			(end 0.120396 0.2794)
			(stroke
				(width 0.1)
				(type default)
			)
			(layer "F.Fab")
		)
		(fp_line
			(start -0.12065 0.3048)
			(end -0.67945 0.3048)
			(stroke
				(width 0.1)
				(type default)
			)
			(layer "F.Fab")
		)
		(fp_line
			(start -0.67945 0.3048)
			(end -0.67945 -0.305054)
			(stroke
				(width 0.1)
				(type default)
			)
			(layer "F.Fab")
		)
		(pad "1" smd circle
			(at -0.40005 0 90)
			(size 0 0)
			(layers "F.Cu" "F.Mask" "F.Paste")
			(net "P12V_NIC0_CO_TIMER")
		)
		(pad "2" smd circle
			(at 0.40005 0 90)
			(size 0 0)
			(layers "F.Cu" "F.Mask" "F.Paste")
			(net "GND")
		)
	)
	(footprint ""
		(layer "F.Cu")
		(at 258.996434 -342.010746 -90)
		(property "Reference" "C4447"
			(at 0 0 270)
			(layer "F.SilkS")
			(hide yes)
			(effects
				(font
					(size 1.27 1.27)
				)
			)
		)
		(property "Value" ""
			(at 0 0 270)
			(layer "F.Fab")
			(effects
				(font
					(size 1.27 1.27)
				)
			)
		)
		(duplicate_pad_numbers_are_jumpers no)
		(fp_line
			(start -0.7874 0.4064)
			(end -0.7874 -0.4064)
			(stroke
				(width 0.1524)
				(type default)
			)
			(layer "F.SilkS")
		)
		(fp_line
			(start 0.7874 0.4064)
			(end -0.7874 0.4064)
			(stroke
				(width 0.1524)
				(type default)
			)
			(layer "F.SilkS")
		)
		(fp_line
			(start -0.7874 -0.4064)
			(end 0.7874 -0.4064)
			(stroke
				(width 0.1524)
				(type default)
			)
			(layer "F.SilkS")
		)
		(fp_line
			(start 0.7874 -0.4064)
			(end 0.7874 0.4064)
			(stroke
				(width 0.1524)
				(type default)
			)
			(layer "F.SilkS")
		)
		(fp_line
			(start -0.67945 0.3048)
			(end -0.67945 -0.305054)
			(stroke
				(width 0.1)
				(type default)
			)
			(layer "F.Fab")
		)
		(fp_line
			(start -0.12065 0.3048)
			(end -0.67945 0.3048)
			(stroke
				(width 0.1)
				(type default)
			)
			(layer "F.Fab")
		)
		(fp_line
			(start 0.120396 0.3048)
			(end 0.120396 0.2794)
			(stroke
				(width 0.1)
				(type default)
			)
			(layer "F.Fab")
		)
		(fp_line
			(start 0.67945 0.3048)
			(end 0.120396 0.3048)
			(stroke
				(width 0.1)
				(type default)
			)
			(layer "F.Fab")
		)
		(fp_line
			(start -0.12065 0.2794)
			(end -0.12065 0.3048)
			(stroke
				(width 0.1)
				(type default)
			)
			(layer "F.Fab")
		)
		(fp_line
			(start 0.120396 0.2794)
			(end -0.12065 0.2794)
			(stroke
				(width 0.1)
				(type default)
			)
			(layer "F.Fab")
		)
		(fp_line
			(start -0.12065 -0.2794)
			(end 0.12065 -0.2794)
			(stroke
				(width 0.1)
				(type default)
			)
			(layer "F.Fab")
		)
		(fp_line
			(start 0.12065 -0.2794)
			(end 0.12065 -0.3048)
			(stroke
				(width 0.1)
				(type default)
			)
			(layer "F.Fab")
		)
		(fp_line
			(start 0.12065 -0.3048)
			(end 0.67945 -0.3048)
			(stroke
				(width 0.1)
				(type default)
			)
			(layer "F.Fab")
		)
		(fp_line
			(start 0.67945 -0.3048)
			(end 0.67945 0.3048)
			(stroke
				(width 0.1)
				(type default)
			)
			(layer "F.Fab")
		)
		(fp_line
			(start -0.67945 -0.305054)
			(end -0.12065 -0.305054)
			(stroke
				(width 0.1)
				(type default)
			)
			(layer "F.Fab")
		)
		(fp_line
			(start -0.12065 -0.305054)
			(end -0.12065 -0.2794)
			(stroke
				(width 0.1)
				(type default)
			)
			(layer "F.Fab")
		)
		(pad "1" smd circle
			(at -0.40005 0 270)
			(size 0 0)
			(layers "F.Cu" "F.Mask" "F.Paste")
			(net "HSC_OC_LT6700_VS")
		)
		(pad "2" smd circle
			(at 0.40005 0 270)
			(size 0 0)
			(layers "F.Cu" "F.Mask" "F.Paste")
			(net "GND")
		)
	)
	(footprint ""
		(layer "F.Cu")
		(at 447.830448 -66.32194 -90)
		(property "Reference" "PC897"
			(at 0 0 270)
			(layer "F.SilkS")
			(hide yes)
			(effects
				(font
					(size 1.27 1.27)
				)
			)
		)
		(property "Value" ""
			(at 0 0 270)
			(layer "F.Fab")
			(effects
				(font
					(size 1.27 1.27)
				)
			)
		)
		(duplicate_pad_numbers_are_jumpers no)
		(fp_line
			(start -0.7874 0.4064)
			(end -0.7874 -0.4064)
			(stroke
				(width 0.1524)
				(type default)
			)
			(layer "F.SilkS")
		)
		(fp_line
			(start 0.7874 0.4064)
			(end -0.7874 0.4064)
			(stroke
				(width 0.1524)
				(type default)
			)
			(layer "F.SilkS")
		)
		(fp_line
			(start -0.7874 -0.4064)
			(end 0.7874 -0.4064)
			(stroke
				(width 0.1524)
				(type default)
			)
			(layer "F.SilkS")
		)
		(fp_line
			(start 0.7874 -0.4064)
			(end 0.7874 0.4064)
			(stroke
				(width 0.1524)
				(type default)
			)
			(layer "F.SilkS")
		)
		(fp_line
			(start -0.67945 0.3048)
			(end -0.67945 -0.305054)
			(stroke
				(width 0.1)
				(type default)
			)
			(layer "F.Fab")
		)
		(fp_line
			(start -0.12065 0.3048)
			(end -0.67945 0.3048)
			(stroke
				(width 0.1)
				(type default)
			)
			(layer "F.Fab")
		)
		(fp_line
			(start 0.120396 0.3048)
			(end 0.120396 0.2794)
			(stroke
				(width 0.1)
				(type default)
			)
			(layer "F.Fab")
		)
		(fp_line
			(start 0.67945 0.3048)
			(end 0.120396 0.3048)
			(stroke
				(width 0.1)
				(type default)
			)
			(layer "F.Fab")
		)
		(fp_line
			(start -0.12065 0.2794)
			(end -0.12065 0.3048)
			(stroke
				(width 0.1)
				(type default)
			)
			(layer "F.Fab")
		)
		(fp_line
			(start 0.120396 0.2794)
			(end -0.12065 0.2794)
			(stroke
				(width 0.1)
				(type default)
			)
			(layer "F.Fab")
		)
		(fp_line
			(start -0.12065 -0.2794)
			(end 0.12065 -0.2794)
			(stroke
				(width 0.1)
				(type default)
			)
			(layer "F.Fab")
		)
		(fp_line
			(start 0.12065 -0.2794)
			(end 0.12065 -0.3048)
			(stroke
				(width 0.1)
				(type default)
			)
			(layer "F.Fab")
		)
		(fp_line
			(start 0.12065 -0.3048)
			(end 0.67945 -0.3048)
			(stroke
				(width 0.1)
				(type default)
			)
			(layer "F.Fab")
		)
		(fp_line
			(start 0.67945 -0.3048)
			(end 0.67945 0.3048)
			(stroke
				(width 0.1)
				(type default)
			)
			(layer "F.Fab")
		)
		(fp_line
			(start -0.67945 -0.305054)
			(end -0.12065 -0.305054)
			(stroke
				(width 0.1)
				(type default)
			)
			(layer "F.Fab")
		)
		(fp_line
			(start -0.12065 -0.305054)
			(end -0.12065 -0.2794)
			(stroke
				(width 0.1)
				(type default)
			)
			(layer "F.Fab")
		)
		(pad "1" smd circle
			(at -0.40005 0 270)
			(size 0 0)
			(layers "F.Cu" "F.Mask" "F.Paste")
			(net "P12V_SSD15_CO_DV_DT")
		)
		(pad "2" smd circle
			(at 0.40005 0 270)
			(size 0 0)
			(layers "F.Cu" "F.Mask" "F.Paste")
			(net "GND")
		)
	)
	(footprint ""
		(layer "F.Cu")
		(at 270.982694 -140.85697)
		(property "Reference" "R238"
			(at 0 0 0)
			(layer "F.SilkS")
			(hide yes)
			(effects
				(font
					(size 1.27 1.27)
				)
			)
		)
		(property "Value" ""
			(at 0 0 0)
			(layer "F.Fab")
			(effects
				(font
					(size 1.27 1.27)
				)
			)
		)
		(duplicate_pad_numbers_are_jumpers no)
		(fp_line
			(start -0.7874 -0.4064)
			(end 0.7874 -0.4064)
			(stroke
				(width 0.1524)
				(type default)
			)
			(layer "F.SilkS")
		)
		(fp_line
			(start -0.7874 0.4064)
			(end -0.7874 -0.4064)
			(stroke
				(width 0.1524)
				(type default)
			)
			(layer "F.SilkS")
		)
		(fp_line
			(start 0.7874 -0.4064)
			(end 0.7874 0.4064)
			(stroke
				(width 0.1524)
				(type default)
			)
			(layer "F.SilkS")
		)
		(fp_line
			(start 0.7874 0.4064)
			(end -0.7874 0.4064)
			(stroke
				(width 0.1524)
				(type default)
			)
			(layer "F.SilkS")
		)
		(fp_line
			(start -0.67945 -0.305054)
			(end -0.12065 -0.305054)
			(stroke
				(width 0.1)
				(type default)
			)
			(layer "F.Fab")
		)
		(fp_line
			(start -0.67945 0.3048)
			(end -0.67945 -0.305054)
			(stroke
				(width 0.1)
				(type default)
			)
			(layer "F.Fab")
		)
		(fp_line
			(start -0.12065 -0.305054)
			(end -0.12065 -0.2794)
			(stroke
				(width 0.1)
				(type default)
			)
			(layer "F.Fab")
		)
		(fp_line
			(start -0.12065 -0.2794)
			(end 0.12065 -0.2794)
			(stroke
				(width 0.1)
				(type default)
			)
			(layer "F.Fab")
		)
		(fp_line
			(start -0.12065 0.2794)
			(end -0.12065 0.3048)
			(stroke
				(width 0.1)
				(type default)
			)
			(layer "F.Fab")
		)
		(fp_line
			(start -0.12065 0.3048)
			(end -0.67945 0.3048)
			(stroke
				(width 0.1)
				(type default)
			)
			(layer "F.Fab")
		)
		(fp_line
			(start 0.120396 0.2794)
			(end -0.12065 0.2794)
			(stroke
				(width 0.1)
				(type default)
			)
			(layer "F.Fab")
		)
		(fp_line
			(start 0.120396 0.3048)
			(end 0.120396 0.2794)
			(stroke
				(width 0.1)
				(type default)
			)
			(layer "F.Fab")
		)
		(fp_line
			(start 0.12065 -0.3048)
			(end 0.67945 -0.3048)
			(stroke
				(width 0.1)
				(type default)
			)
			(layer "F.Fab")
		)
		(fp_line
			(start 0.12065 -0.2794)
			(end 0.12065 -0.3048)
			(stroke
				(width 0.1)
				(type default)
			)
			(layer "F.Fab")
		)
		(fp_line
			(start 0.67945 -0.3048)
			(end 0.67945 0.3048)
			(stroke
				(width 0.1)
				(type default)
			)
			(layer "F.Fab")
		)
		(fp_line
			(start 0.67945 0.3048)
			(end 0.120396 0.3048)
			(stroke
				(width 0.1)
				(type default)
			)
			(layer "F.Fab")
		)
		(pad "1" smd circle
			(at -0.40005 0)
			(size 0 0)
			(layers "F.Cu" "F.Mask" "F.Paste")
			(net "NIC4_BIF2_N")
		)
		(pad "2" smd circle
			(at 0.40005 0)
			(size 0 0)
			(layers "F.Cu" "F.Mask" "F.Paste")
			(net "GND")
		)
	)
	(footprint ""
		(layer "F.Cu")
		(at 142.262352 -262.645652 90)
		(property "Reference" "C3246"
			(at 0 0 90)
			(layer "F.SilkS")
			(hide yes)
			(effects
				(font
					(size 1.27 1.27)
				)
			)
		)
		(property "Value" ""
			(at 0 0 90)
			(layer "F.Fab")
			(effects
				(font
					(size 1.27 1.27)
				)
			)
		)
		(duplicate_pad_numbers_are_jumpers no)
		(fp_line
			(start 0.299974 -0.150114)
			(end 0.299974 0.150114)
			(stroke
				(width 0.1)
				(type default)
			)
			(layer "F.Fab")
		)
		(fp_line
			(start -0.299974 -0.150114)
			(end 0.299974 -0.150114)
			(stroke
				(width 0.1)
				(type default)
			)
			(layer "F.Fab")
		)
		(fp_line
			(start 0.299974 0.150114)
			(end -0.299974 0.150114)
			(stroke
				(width 0.1)
				(type default)
			)
			(layer "F.Fab")
		)
		(fp_line
			(start -0.299974 0.150114)
			(end -0.299974 -0.150114)
			(stroke
				(width 0.1)
				(type default)
			)
			(layer "F.Fab")
		)
		(pad "1" smd rect
			(at -0.2667 0 90)
			(size 0.3048 0.381)
			(layers "F.Cu" "F.Mask" "F.Paste")
			(net "P1V8_VDDA_PEX1")
		)
		(pad "2" smd rect
			(at 0.2667 0 90)
			(size 0.3048 0.381)
			(layers "F.Cu" "F.Mask" "F.Paste")
			(net "GND")
		)
	)
	(footprint ""
		(layer "F.Cu")
		(at 283.416502 -350.098614 90)
		(property "Reference" "C2355"
			(at 0 0 90)
			(layer "F.SilkS")
			(hide yes)
			(effects
				(font
					(size 1.27 1.27)
				)
			)
		)
		(property "Value" ""
			(at 0 0 90)
			(layer "F.Fab")
			(effects
				(font
					(size 1.27 1.27)
				)
			)
		)
		(duplicate_pad_numbers_are_jumpers no)
		(fp_line
			(start 0.299974 -0.150114)
			(end 0.299974 0.150114)
			(stroke
				(width 0.1)
				(type default)
			)
			(layer "F.Fab")
		)
		(fp_line
			(start -0.299974 -0.150114)
			(end 0.299974 -0.150114)
			(stroke
				(width 0.1)
				(type default)
			)
			(layer "F.Fab")
		)
		(fp_line
			(start 0.299974 0.150114)
			(end -0.299974 0.150114)
			(stroke
				(width 0.1)
				(type default)
			)
			(layer "F.Fab")
		)
		(fp_line
			(start -0.299974 0.150114)
			(end -0.299974 -0.150114)
			(stroke
				(width 0.1)
				(type default)
			)
			(layer "F.Fab")
		)
		(pad "1" smd rect
			(at -0.2667 0 90)
			(size 0.3048 0.381)
			(layers "F.Cu" "F.Mask" "F.Paste")
			(net "P5E_PEX2_STN4_TX_DP<72>")
		)
		(pad "2" smd rect
			(at 0.2667 0 90)
			(size 0.3048 0.381)
			(layers "F.Cu" "F.Mask" "F.Paste")
			(net "P5E_PEX2_STN4_TX_C_DP<72>")
		)
	)
	(footprint ""
		(layer "F.Cu")
		(at 242.447318 -266.794996)
		(property "Reference" "L114"
			(at 0 0 0)
			(layer "F.SilkS")
			(hide yes)
			(effects
				(font
					(size 1.27 1.27)
				)
			)
		)
		(property "Value" ""
			(at 0 0 0)
			(layer "F.Fab")
			(effects
				(font
					(size 1.27 1.27)
				)
			)
		)
		(duplicate_pad_numbers_are_jumpers no)
		(fp_line
			(start -2.248154 -4.9911)
			(end -2.248154 -1.772412)
			(stroke
				(width 0.1524)
				(type default)
			)
			(layer "F.SilkS")
		)
		(fp_line
			(start -2.248154 1.653286)
			(end -2.248154 4.9911)
			(stroke
				(width 0.1524)
				(type default)
			)
			(layer "F.SilkS")
		)
		(fp_line
			(start -2.248154 4.9911)
			(end 2.248154 4.9911)
			(stroke
				(width 0.1524)
				(type default)
			)
			(layer "F.SilkS")
		)
		(fp_line
			(start 2.248154 -4.9911)
			(end -2.248154 -4.9911)
			(stroke
				(width 0.1524)
				(type default)
			)
			(layer "F.SilkS")
		)
		(fp_line
			(start 2.248154 -1.860296)
			(end 2.248154 -4.9911)
			(stroke
				(width 0.1524)
				(type default)
			)
			(layer "F.SilkS")
		)
		(fp_line
			(start 2.248154 4.9911)
			(end 2.248154 1.675384)
			(stroke
				(width 0.1524)
				(type default)
			)
			(layer "F.SilkS")
		)
		(fp_line
			(start -1.700022 -0.899922)
			(end -1.700022 0.899922)
			(stroke
				(width 0.1)
				(type default)
			)
			(layer "F.Fab")
		)
		(fp_line
			(start -1.700022 0.899922)
			(end 1.700022 0.899922)
			(stroke
				(width 0.1)
				(type default)
			)
			(layer "F.Fab")
		)
		(fp_line
			(start 1.700022 -0.899922)
			(end -1.700022 -0.899922)
			(stroke
				(width 0.1)
				(type default)
			)
			(layer "F.Fab")
		)
		(fp_line
			(start 1.700022 0.899922)
			(end 1.700022 -0.899922)
			(stroke
				(width 0.1)
				(type default)
			)
			(layer "F.Fab")
		)
		(pad "1" smd rect
			(at -1.575054 0)
			(size 1.1684 9.8044)
			(layers "F.Cu" "F.Mask" "F.Paste")
			(net "P1V25_PEX2")
		)
		(pad "2" smd rect
			(at 1.575054 0)
			(size 1.1684 9.8044)
			(layers "F.Cu" "F.Mask" "F.Paste")
			(net "P1V25_SERDES_VDDPLL_PEX2")
		)
	)
)
